(kicad_pcb
	(version 20260206)
	(generator "pcbnew")
	(generator_version "10.0")
	(general
		(thickness 1.6)
		(legacy_teardrops no)
	)
	(paper "A4")
	(title_block
		(title "03242023_DA0F0TMBIJ0_F0T_Motherboard_J_brd_V01_OCP.brd")
		(comment 1 "Grand Teton / footprints 1114-1118 of 6105")
	)
	(layers
		(0 "F.Cu" signal "TOP")
		(4 "In1.Cu" signal "GND")
		(6 "In2.Cu" signal "IN1")
		(8 "In3.Cu" signal "GND1")
		(10 "In4.Cu" signal "IN2")
		(12 "In5.Cu" signal "GND2")
		(14 "In6.Cu" signal "IN3")
		(16 "In7.Cu" signal "GND3")
		(18 "In8.Cu" signal "VCC")
		(20 "In9.Cu" signal "VCC1")
		(22 "In10.Cu" signal "GND4")
		(24 "In11.Cu" signal "IN4")
		(26 "In12.Cu" signal "GND5")
		(28 "In13.Cu" signal "IN5")
		(30 "In14.Cu" signal "GND6")
		(32 "In15.Cu" signal "IN6")
		(34 "In16.Cu" signal "GND7")
		(2 "B.Cu" signal "BOTTOM")
		(9 "F.Adhes" user "F.Adhesive")
		(11 "B.Adhes" user "B.Adhesive")
		(13 "F.Paste" user "Package Geometry/Pastemask Top")
		(15 "B.Paste" user "Package Geometry/Pastemask Bottom")
		(5 "F.SilkS" user "Ref Des/Silkscreen Top")
		(7 "B.SilkS" user "Ref Des/Silkscreen Bottom")
		(1 "F.Mask" user "Board Geometry/Soldermask Top")
		(3 "B.Mask" user "Board Geometry/Soldermask Bottom")
		(17 "Dwgs.User" user "User.Drawings")
		(19 "Cmts.User" user "User.Comments")
		(21 "Eco1.User" user "User.Eco1")
		(23 "Eco2.User" user "User.Eco2")
		(25 "Edge.Cuts" user "Board Geometry/Outline")
		(27 "Margin" user)
		(31 "F.CrtYd" user "Package Geometry/Place Bound Top")
		(29 "B.CrtYd" user "Package Geometry/Place Bound Bottom")
		(35 "F.Fab" user "Ref Des/Assembly Top")
		(33 "B.Fab" user "Ref Des/Assembly Bottom")
	)
	(footprint ""
		(layer "F.Cu")
		(at 49.648618 -178.060604 90)
		(property "Reference" "PC429"
			(at 0 0 90)
			(layer "F.SilkS")
			(hide yes)
			(effects
				(font
					(size 1.27 1.27)
				)
			)
		)
		(property "Value" ""
			(at 0 0 90)
			(layer "F.Fab")
			(effects
				(font
					(size 1.27 1.27)
				)
			)
		)
		(duplicate_pad_numbers_are_jumpers no)
		(fp_line
			(start 0.7874 -0.4064)
			(end 0.7874 0.4064)
			(stroke
				(width 0.1524)
				(type default)
			)
			(layer "F.SilkS")
		)
		(fp_line
			(start -0.7874 -0.4064)
			(end 0.7874 -0.4064)
			(stroke
				(width 0.1524)
				(type default)
			)
			(layer "F.SilkS")
		)
		(fp_line
			(start 0.7874 0.4064)
			(end -0.7874 0.4064)
			(stroke
				(width 0.1524)
				(type default)
			)
			(layer "F.SilkS")
		)
		(fp_line
			(start -0.7874 0.4064)
			(end -0.7874 -0.4064)
			(stroke
				(width 0.1524)
				(type default)
			)
			(layer "F.SilkS")
		)
		(fp_line
			(start -0.12065 -0.305054)
			(end -0.12065 -0.2794)
			(stroke
				(width 0.1)
				(type default)
			)
			(layer "F.Fab")
		)
		(fp_line
			(start -0.67945 -0.305054)
			(end -0.12065 -0.305054)
			(stroke
				(width 0.1)
				(type default)
			)
			(layer "F.Fab")
		)
		(fp_line
			(start 0.67945 -0.3048)
			(end 0.67945 0.3048)
			(stroke
				(width 0.1)
				(type default)
			)
			(layer "F.Fab")
		)
		(fp_line
			(start 0.12065 -0.3048)
			(end 0.67945 -0.3048)
			(stroke
				(width 0.1)
				(type default)
			)
			(layer "F.Fab")
		)
		(fp_line
			(start 0.12065 -0.2794)
			(end 0.12065 -0.3048)
			(stroke
				(width 0.1)
				(type default)
			)
			(layer "F.Fab")
		)
		(fp_line
			(start -0.12065 -0.2794)
			(end 0.12065 -0.2794)
			(stroke
				(width 0.1)
				(type default)
			)
			(layer "F.Fab")
		)
		(fp_line
			(start 0.120396 0.2794)
			(end -0.12065 0.2794)
			(stroke
				(width 0.1)
				(type default)
			)
			(layer "F.Fab")
		)
		(fp_line
			(start -0.12065 0.2794)
			(end -0.12065 0.3048)
			(stroke
				(width 0.1)
				(type default)
			)
			(layer "F.Fab")
		)
		(fp_line
			(start 0.67945 0.3048)
			(end 0.120396 0.3048)
			(stroke
				(width 0.1)
				(type default)
			)
			(layer "F.Fab")
		)
		(fp_line
			(start 0.120396 0.3048)
			(end 0.120396 0.2794)
			(stroke
				(width 0.1)
				(type default)
			)
			(layer "F.Fab")
		)
		(fp_line
			(start -0.12065 0.3048)
			(end -0.67945 0.3048)
			(stroke
				(width 0.1)
				(type default)
			)
			(layer "F.Fab")
		)
		(fp_line
			(start -0.67945 0.3048)
			(end -0.67945 -0.305054)
			(stroke
				(width 0.1)
				(type default)
			)
			(layer "F.Fab")
		)
		(pad "1" smd circle
			(at -0.40005 0 90)
			(size 0 0)
			(layers "F.Cu" "F.Mask" "F.Paste")
			(net "SW_P12V_PVCCINFAON_CPU1_FLT")
		)
		(pad "2" smd circle
			(at 0.40005 0 90)
			(size 0 0)
			(layers "F.Cu" "F.Mask" "F.Paste")
			(net "GND")
		)
	)
	(footprint ""
		(layer "F.Cu")
		(at 152.70988 -105.755948 180)
		(property "Reference" "R3234"
			(at 0 0 180)
			(layer "F.SilkS")
			(hide yes)
			(effects
				(font
					(size 1.27 1.27)
				)
			)
		)
		(property "Value" ""
			(at 0 0 180)
			(layer "F.Fab")
			(effects
				(font
					(size 1.27 1.27)
				)
			)
		)
		(duplicate_pad_numbers_are_jumpers no)
		(fp_line
			(start 0.7874 0.4064)
			(end -0.7874 0.4064)
			(stroke
				(width 0.1524)
				(type default)
			)
			(layer "F.SilkS")
		)
		(fp_line
			(start 0.7874 -0.4064)
			(end 0.7874 0.4064)
			(stroke
				(width 0.1524)
				(type default)
			)
			(layer "F.SilkS")
		)
		(fp_line
			(start -0.7874 0.4064)
			(end -0.7874 -0.4064)
			(stroke
				(width 0.1524)
				(type default)
			)
			(layer "F.SilkS")
		)
		(fp_line
			(start -0.7874 -0.4064)
			(end 0.7874 -0.4064)
			(stroke
				(width 0.1524)
				(type default)
			)
			(layer "F.SilkS")
		)
		(fp_line
			(start 0.67945 0.3048)
			(end 0.120396 0.3048)
			(stroke
				(width 0.1)
				(type default)
			)
			(layer "F.Fab")
		)
		(fp_line
			(start 0.67945 -0.3048)
			(end 0.67945 0.3048)
			(stroke
				(width 0.1)
				(type default)
			)
			(layer "F.Fab")
		)
		(fp_line
			(start 0.12065 -0.2794)
			(end 0.12065 -0.3048)
			(stroke
				(width 0.1)
				(type default)
			)
			(layer "F.Fab")
		)
		(fp_line
			(start 0.12065 -0.3048)
			(end 0.67945 -0.3048)
			(stroke
				(width 0.1)
				(type default)
			)
			(layer "F.Fab")
		)
		(fp_line
			(start 0.120396 0.3048)
			(end 0.120396 0.2794)
			(stroke
				(width 0.1)
				(type default)
			)
			(layer "F.Fab")
		)
		(fp_line
			(start 0.120396 0.2794)
			(end -0.12065 0.2794)
			(stroke
				(width 0.1)
				(type default)
			)
			(layer "F.Fab")
		)
		(fp_line
			(start -0.12065 0.3048)
			(end -0.67945 0.3048)
			(stroke
				(width 0.1)
				(type default)
			)
			(layer "F.Fab")
		)
		(fp_line
			(start -0.12065 0.2794)
			(end -0.12065 0.3048)
			(stroke
				(width 0.1)
				(type default)
			)
			(layer "F.Fab")
		)
		(fp_line
			(start -0.12065 -0.2794)
			(end 0.12065 -0.2794)
			(stroke
				(width 0.1)
				(type default)
			)
			(layer "F.Fab")
		)
		(fp_line
			(start -0.12065 -0.305054)
			(end -0.12065 -0.2794)
			(stroke
				(width 0.1)
				(type default)
			)
			(layer "F.Fab")
		)
		(fp_line
			(start -0.67945 0.3048)
			(end -0.67945 -0.305054)
			(stroke
				(width 0.1)
				(type default)
			)
			(layer "F.Fab")
		)
		(fp_line
			(start -0.67945 -0.305054)
			(end -0.12065 -0.305054)
			(stroke
				(width 0.1)
				(type default)
			)
			(layer "F.Fab")
		)
		(pad "1" smd circle
			(at -0.40005 0 180)
			(size 0 0)
			(layers "F.Cu" "F.Mask" "F.Paste")
			(net "OCP_V3_2_AUX_PWR_EN")
		)
		(pad "2" smd circle
			(at 0.40005 0 180)
			(size 0 0)
			(layers "F.Cu" "F.Mask" "F.Paste")
			(net "OCP_V3_2_AUX_PWR_EN_R3")
		)
	)
	(footprint ""
		(layer "F.Cu")
		(at 327.29678 -34.201608 45)
		(property "Reference" "R1721"
			(at 0 0 45)
			(layer "F.SilkS")
			(hide yes)
			(effects
				(font
					(size 1.27 1.27)
				)
			)
		)
		(property "Value" ""
			(at 0 0 45)
			(layer "F.Fab")
			(effects
				(font
					(size 1.27 1.27)
				)
			)
		)
		(duplicate_pad_numbers_are_jumpers no)
		(fp_line
			(start -0.787389 -0.406267)
			(end 0.787389 -0.406267)
			(stroke
				(width 0.1524)
				(type default)
			)
			(layer "F.SilkS")
		)
		(fp_line
			(start -0.787389 0.406267)
			(end -0.787389 -0.406267)
			(stroke
				(width 0.1524)
				(type default)
			)
			(layer "F.SilkS")
		)
		(fp_line
			(start 0.787389 -0.406267)
			(end 0.787389 0.406267)
			(stroke
				(width 0.1524)
				(type default)
			)
			(layer "F.SilkS")
		)
		(fp_line
			(start 0.787389 0.406267)
			(end -0.787389 0.406267)
			(stroke
				(width 0.1524)
				(type default)
			)
			(layer "F.SilkS")
		)
		(fp_line
			(start -0.679446 -0.305149)
			(end -0.120695 -0.304969)
			(stroke
				(width 0.1)
				(type default)
			)
			(layer "F.Fab")
		)
		(fp_line
			(start -0.120695 -0.304969)
			(end -0.120695 -0.279466)
			(stroke
				(width 0.1)
				(type default)
			)
			(layer "F.Fab")
		)
		(fp_line
			(start -0.120695 -0.279466)
			(end 0.120695 -0.279466)
			(stroke
				(width 0.1)
				(type default)
			)
			(layer "F.Fab")
		)
		(fp_line
			(start -0.679446 0.30479)
			(end -0.679446 -0.305149)
			(stroke
				(width 0.1)
				(type default)
			)
			(layer "F.Fab")
		)
		(fp_line
			(start 0.120515 -0.30479)
			(end 0.679446 -0.30479)
			(stroke
				(width 0.1)
				(type default)
			)
			(layer "F.Fab")
		)
		(fp_line
			(start 0.120695 -0.279466)
			(end 0.120515 -0.30479)
			(stroke
				(width 0.1)
				(type default)
			)
			(layer "F.Fab")
		)
		(fp_line
			(start -0.120695 0.279466)
			(end -0.120515 0.30479)
			(stroke
				(width 0.1)
				(type default)
			)
			(layer "F.Fab")
		)
		(fp_line
			(start -0.120515 0.30479)
			(end -0.679446 0.30479)
			(stroke
				(width 0.1)
				(type default)
			)
			(layer "F.Fab")
		)
		(fp_line
			(start 0.679446 -0.30479)
			(end 0.679446 0.30479)
			(stroke
				(width 0.1)
				(type default)
			)
			(layer "F.Fab")
		)
		(fp_line
			(start 0.120335 0.279466)
			(end -0.120695 0.279466)
			(stroke
				(width 0.1)
				(type default)
			)
			(layer "F.Fab")
		)
		(fp_line
			(start 0.120515 0.30479)
			(end 0.120335 0.279466)
			(stroke
				(width 0.1)
				(type default)
			)
			(layer "F.Fab")
		)
		(fp_line
			(start 0.679446 0.30479)
			(end 0.120515 0.30479)
			(stroke
				(width 0.1)
				(type default)
			)
			(layer "F.Fab")
		)
		(pad "1" smd circle
			(at -0.40005 0 45)
			(size 0 0)
			(layers "F.Cu" "F.Mask" "F.Paste")
			(net "XTAL_PCH_RTC2_R")
		)
		(pad "2" smd circle
			(at 0.40005 0 45)
			(size 0 0)
			(layers "F.Cu" "F.Mask" "F.Paste")
			(net "XTAL_PCH_RTC2")
		)
	)
	(footprint ""
		(layer "F.Cu")
		(at 26.97988 -428.081948)
		(property "Reference" "U252"
			(at -2.56286 1.98247 0)
			(unlocked yes)
			(layer "F.SilkS")
			(effects
				(font
					(size 0.7874 0.5842)
					(thickness 0.1524)
				)
				(justify left)
			)
		)
		(property "Value" ""
			(at 0 0 0)
			(layer "F.Fab")
			(effects
				(font
					(size 1.27 1.27)
				)
			)
		)
		(duplicate_pad_numbers_are_jumpers no)
		(fp_line
			(start -1.3462 -1.100074)
			(end -0.670052 -1.100074)
			(stroke
				(width 0.1524)
				(type default)
			)
			(layer "F.SilkS")
		)
		(fp_line
			(start -1.3462 1.100074)
			(end -1.3462 -1.100074)
			(stroke
				(width 0.1524)
				(type default)
			)
			(layer "F.SilkS")
		)
		(fp_line
			(start -0.670052 -1.100074)
			(end 0 -0.381)
			(stroke
				(width 0.1524)
				(type default)
			)
			(layer "F.SilkS")
		)
		(fp_line
			(start 0 -0.381)
			(end 0.670052 -1.100074)
			(stroke
				(width 0.1524)
				(type default)
			)
			(layer "F.SilkS")
		)
		(fp_line
			(start 0.670052 -1.100074)
			(end 1.3462 -1.100074)
			(stroke
				(width 0.1524)
				(type default)
			)
			(layer "F.SilkS")
		)
		(fp_line
			(start 1.3462 -1.100074)
			(end 1.3462 1.100074)
			(stroke
				(width 0.1524)
				(type default)
			)
			(layer "F.SilkS")
		)
		(fp_line
			(start 1.3462 1.100074)
			(end -1.3462 1.100074)
			(stroke
				(width 0.1524)
				(type default)
			)
			(layer "F.SilkS")
		)
		(fp_poly
			(pts
				(xy -2.0574 -0.634746) (xy -2.8194 -0.253746) (xy -2.8194 -1.015746)
			)
			(stroke
				(width 0)
				(type default)
			)
			(fill yes)
			(layer "F.SilkS")
		)
		(fp_line
			(start -1.100074 -0.8001)
			(end -0.670052 -0.8001)
			(stroke
				(width 0.1)
				(type default)
			)
			(layer "F.Fab")
		)
		(fp_line
			(start -1.100074 0.8001)
			(end -1.100074 -0.8001)
			(stroke
				(width 0.1)
				(type default)
			)
			(layer "F.Fab")
		)
		(fp_line
			(start -0.670052 -1.100074)
			(end 0.670052 -1.100074)
			(stroke
				(width 0.1)
				(type default)
			)
			(layer "F.Fab")
		)
		(fp_line
			(start -0.670052 -0.8001)
			(end -0.670052 -1.100074)
			(stroke
				(width 0.1)
				(type default)
			)
			(layer "F.Fab")
		)
		(fp_line
			(start -0.670052 0.8001)
			(end -1.100074 0.8001)
			(stroke
				(width 0.1)
				(type default)
			)
			(layer "F.Fab")
		)
		(fp_line
			(start -0.670052 0.8001)
			(end -0.670052 -0.8001)
			(stroke
				(width 0.1)
				(type default)
			)
			(layer "F.Fab")
		)
		(fp_line
			(start -0.670052 1.100074)
			(end -0.670052 0.8001)
			(stroke
				(width 0.1)
				(type default)
			)
			(layer "F.Fab")
		)
		(fp_line
			(start 0.670052 -1.100074)
			(end 0.670052 -0.8001)
			(stroke
				(width 0.1)
				(type default)
			)
			(layer "F.Fab")
		)
		(fp_line
			(start 0.670052 -0.8001)
			(end 0.670052 0.8001)
			(stroke
				(width 0.1)
				(type default)
			)
			(layer "F.Fab")
		)
		(fp_line
			(start 0.670052 -0.8001)
			(end 1.100074 -0.8001)
			(stroke
				(width 0.1)
				(type default)
			)
			(layer "F.Fab")
		)
		(fp_line
			(start 0.670052 0.8001)
			(end 0.670052 1.100074)
			(stroke
				(width 0.1)
				(type default)
			)
			(layer "F.Fab")
		)
		(fp_line
			(start 0.670052 1.100074)
			(end -0.670052 1.100074)
			(stroke
				(width 0.1)
				(type default)
			)
			(layer "F.Fab")
		)
		(fp_line
			(start 1.100074 -0.8001)
			(end 1.100074 0.8001)
			(stroke
				(width 0.1)
				(type default)
			)
			(layer "F.Fab")
		)
		(fp_line
			(start 1.100074 0.8001)
			(end 0.670052 0.8001)
			(stroke
				(width 0.1)
				(type default)
			)
			(layer "F.Fab")
		)
		(fp_poly
			(pts
				(xy -1.524 -0.649986) (xy -2.286 -1.030986) (xy -2.286 -0.268986)
			)
			(stroke
				(width 0)
				(type default)
			)
			(fill yes)
			(layer "F.Fab")
		)
		(pad "1" smd rect
			(at -0.94996 -0.649986 270)
			(size 0.4064 0.508)
			(layers "F.Cu" "F.Mask" "F.Paste")
			(net "RST_PERST_SWB_R_N")
		)
		(pad "2" smd rect
			(at -0.94996 0 270)
			(size 0.4064 0.508)
			(layers "F.Cu" "F.Mask" "F.Paste")
			(net "GND")
		)
		(pad "3" smd rect
			(at -0.94996 0.649986 270)
			(size 0.4064 0.508)
			(layers "F.Cu" "F.Mask" "F.Paste")
			(net "RST_PERST_SWB_R_N")
		)
		(pad "4" smd rect
			(at 0.94996 0.649986 270)
			(size 0.4064 0.508)
			(layers "F.Cu" "F.Mask" "F.Paste")
			(net "RST_PERST_1_SWB_BUF_R_N")
		)
		(pad "5" smd rect
			(at 0.94996 0 270)
			(size 0.4064 0.508)
			(layers "F.Cu" "F.Mask" "F.Paste")
			(net "P3V3_AUX")
		)
		(pad "6" smd rect
			(at 0.94996 -0.649986 270)
			(size 0.4064 0.508)
			(layers "F.Cu" "F.Mask" "F.Paste")
			(net "RST_PERST_0_SWB_BUF_R_N")
		)
	)
	(footprint ""
		(layer "F.Cu")
		(at 209.4992 -111.4298 -90)
		(property "Reference" "U338"
			(at -4.24053 1.8542 0)
			(unlocked yes)
			(layer "F.SilkS")
			(effects
				(font
					(size 0.7874 0.5842)
					(thickness 0.1524)
				)
				(justify left)
			)
		)
		(property "Value" ""
			(at 0 0 270)
			(layer "F.Fab")
			(effects
				(font
					(size 1.27 1.27)
				)
			)
		)
		(duplicate_pad_numbers_are_jumpers no)
		(fp_line
			(start -1.868424 1.519936)
			(end 1.868424 1.519936)
			(stroke
				(width 0.1524)
				(type default)
			)
			(layer "F.SilkS")
		)
		(fp_line
			(start 1.868424 1.519936)
			(end 1.868424 -1.519936)
			(stroke
				(width 0.1524)
				(type default)
			)
			(layer "F.SilkS")
		)
		(fp_line
			(start -1.868424 -1.519936)
			(end -1.868424 1.519936)
			(stroke
				(width 0.1524)
				(type default)
			)
			(layer "F.SilkS")
		)
		(fp_line
			(start 1.868424 -1.519936)
			(end -1.868424 -1.519936)
			(stroke
				(width 0.1524)
				(type default)
			)
			(layer "F.SilkS")
		)
		(fp_line
			(start -0.700024 1.519936)
			(end 0.700024 1.519936)
			(stroke
				(width 0.1)
				(type default)
			)
			(layer "F.Fab")
		)
		(fp_line
			(start 0.700024 1.519936)
			(end 0.700024 -1.519936)
			(stroke
				(width 0.1)
				(type default)
			)
			(layer "F.Fab")
		)
		(fp_line
			(start -0.700024 -1.519936)
			(end -0.700024 1.519936)
			(stroke
				(width 0.1)
				(type default)
			)
			(layer "F.Fab")
		)
		(fp_line
			(start 0.700024 -1.519936)
			(end -0.700024 -1.519936)
			(stroke
				(width 0.1)
				(type default)
			)
			(layer "F.Fab")
		)
		(pad "1" smd rect
			(at -1.18491 -0.94996 180)
			(size 0.6096 1.0668)
			(layers "F.Cu" "F.Mask" "F.Paste")
			(net "UV_P2V5_COMP")
		)
		(pad "2" smd rect
			(at -1.18491 0.94996 180)
			(size 0.6096 1.0668)
			(layers "F.Cu" "F.Mask" "F.Paste")
			(net "GND")
		)
		(pad "3" smd rect
			(at 1.18491 0 180)
			(size 0.6096 1.0668)
			(layers "F.Cu" "F.Mask" "F.Paste")
			(net "Net_8627")
		)
	)
)
